(kicad_pcb
	(version 20260206)
	(generator "pcbnew")
	(generator_version "10.0")
	(general
		(thickness 1.6)
		(legacy_teardrops no)
	)
	(paper "A4")
	(title_block
		(title "03242023_DA0F0TMBIJ0_F0T_Motherboard_J_brd_V01_OCP.brd")
		(comment 1 "Grand Teton / footprints 15-19 of 6105")
	)
	(layers
		(0 "F.Cu" signal "TOP")
		(4 "In1.Cu" signal "GND")
		(6 "In2.Cu" signal "IN1")
		(8 "In3.Cu" signal "GND1")
		(10 "In4.Cu" signal "IN2")
		(12 "In5.Cu" signal "GND2")
		(14 "In6.Cu" signal "IN3")
		(16 "In7.Cu" signal "GND3")
		(18 "In8.Cu" signal "VCC")
		(20 "In9.Cu" signal "VCC1")
		(22 "In10.Cu" signal "GND4")
		(24 "In11.Cu" signal "IN4")
		(26 "In12.Cu" signal "GND5")
		(28 "In13.Cu" signal "IN5")
		(30 "In14.Cu" signal "GND6")
		(32 "In15.Cu" signal "IN6")
		(34 "In16.Cu" signal "GND7")
		(2 "B.Cu" signal "BOTTOM")
		(9 "F.Adhes" user "F.Adhesive")
		(11 "B.Adhes" user "B.Adhesive")
		(13 "F.Paste" user "Package Geometry/Pastemask Top")
		(15 "B.Paste" user "Package Geometry/Pastemask Bottom")
		(5 "F.SilkS" user "Ref Des/Silkscreen Top")
		(7 "B.SilkS" user "Ref Des/Silkscreen Bottom")
		(1 "F.Mask" user "Board Geometry/Soldermask Top")
		(3 "B.Mask" user "Board Geometry/Soldermask Bottom")
		(17 "Dwgs.User" user "User.Drawings")
		(19 "Cmts.User" user "User.Comments")
		(21 "Eco1.User" user "User.Eco1")
		(23 "Eco2.User" user "User.Eco2")
		(25 "Edge.Cuts" user "Board Geometry/Outline")
		(27 "Margin" user)
		(31 "F.CrtYd" user "Package Geometry/Place Bound Top")
		(29 "B.CrtYd" user "Package Geometry/Place Bound Bottom")
		(35 "F.Fab" user "Ref Des/Assembly Top")
		(33 "B.Fab" user "Ref Des/Assembly Bottom")
	)
	(footprint ""
		(layer "F.Cu")
		(at 104.93121 -60.128404)
		(property "Reference" "U85"
			(at -3.9243 0.42545 0)
			(unlocked yes)
			(layer "F.SilkS")
			(effects
				(font
					(size 0.7874 0.5842)
					(thickness 0.1524)
				)
			)
		)
		(property "Value" ""
			(at 0 0 0)
			(layer "F.Fab")
			(effects
				(font
					(size 1.27 1.27)
				)
			)
		)
		(duplicate_pad_numbers_are_jumpers no)
		(fp_line
			(start -1.7272 1.1176)
			(end -1.7272 -1.1176)
			(stroke
				(width 0.1524)
				(type default)
			)
			(layer "F.SilkS")
		)
		(fp_line
			(start -0.254 -1.1176)
			(end -1.7272 -1.1176)
			(stroke
				(width 0.1524)
				(type default)
			)
			(layer "F.SilkS")
		)
		(fp_line
			(start 0 -0.7366)
			(end -0.254 -1.1176)
			(stroke
				(width 0.1524)
				(type default)
			)
			(layer "F.SilkS")
		)
		(fp_line
			(start 0.254 -1.1176)
			(end 0 -0.7366)
			(stroke
				(width 0.1524)
				(type default)
			)
			(layer "F.SilkS")
		)
		(fp_line
			(start 1.7272 -1.1176)
			(end 0.254 -1.1176)
			(stroke
				(width 0.1524)
				(type default)
			)
			(layer "F.SilkS")
		)
		(fp_line
			(start 1.7272 -1.1176)
			(end 1.7272 1.1176)
			(stroke
				(width 0.1524)
				(type default)
			)
			(layer "F.SilkS")
		)
		(fp_line
			(start 1.7272 1.1176)
			(end -1.7272 1.1176)
			(stroke
				(width 0.1524)
				(type default)
			)
			(layer "F.SilkS")
		)
		(fp_poly
			(pts
				(xy -2.7178 -0.268986) (xy -2.7178 -1.030986) (xy -1.9558 -0.649986)
			)
			(stroke
				(width 0)
				(type default)
			)
			(fill yes)
			(layer "F.SilkS")
		)
		(fp_line
			(start -1.5748 -1.1176)
			(end -1.5748 1.1176)
			(stroke
				(width 0.1)
				(type default)
			)
			(layer "F.Fab")
		)
		(fp_line
			(start -1.5748 1.1176)
			(end 1.5748 1.1176)
			(stroke
				(width 0.1)
				(type default)
			)
			(layer "F.Fab")
		)
		(fp_line
			(start 1.5748 -1.1176)
			(end -1.5748 -1.1176)
			(stroke
				(width 0.1)
				(type default)
			)
			(layer "F.Fab")
		)
		(fp_line
			(start 1.5748 1.1176)
			(end 1.5748 -1.1176)
			(stroke
				(width 0.1)
				(type default)
			)
			(layer "F.Fab")
		)
		(fp_poly
			(pts
				(xy -1.9558 -0.649986) (xy -2.7178 -0.268986) (xy -2.7178 -1.030986)
			)
			(stroke
				(width 0)
				(type default)
			)
			(fill yes)
			(layer "F.Fab")
		)
		(pad "1" smd rect
			(at -0.999998 -0.649986 270)
			(size 0.3556 1.1176)
			(layers "F.Cu" "F.Mask" "F.Paste")
			(net "JTAG_BMC_PCH_TCK")
		)
		(pad "2" smd rect
			(at -0.999998 0 270)
			(size 0.3556 1.1176)
			(layers "F.Cu" "F.Mask" "F.Paste")
			(net "GND")
		)
		(pad "3" smd rect
			(at -0.999998 0.649986 270)
			(size 0.3556 1.1176)
			(layers "F.Cu" "F.Mask" "F.Paste")
			(net "JTAG_BMC_CPU_TCK")
		)
		(pad "4" smd rect
			(at 0.999998 0.649986 270)
			(size 0.3556 1.1176)
			(layers "F.Cu" "F.Mask" "F.Paste")
			(net "JTAG_BMC_DBP_TCK")
		)
		(pad "5" smd rect
			(at 0.999998 0 270)
			(size 0.3556 1.1176)
			(layers "F.Cu" "F.Mask" "F.Paste")
			(net "P3V3_AUX")
		)
		(pad "6" smd rect
			(at 0.999998 -0.649986 270)
			(size 0.3556 1.1176)
			(layers "F.Cu" "F.Mask" "F.Paste")
			(net "FM_JTAG_TCK_MUX_SEL")
		)
	)
	(footprint ""
		(layer "F.Cu")
		(at 314.058808 -402.371052 -90)
		(property "Reference" "C1573"
			(at 0 0 270)
			(layer "F.SilkS")
			(hide yes)
			(effects
				(font
					(size 1.27 1.27)
				)
			)
		)
		(property "Value" ""
			(at 0 0 270)
			(layer "F.Fab")
			(effects
				(font
					(size 1.27 1.27)
				)
			)
		)
		(duplicate_pad_numbers_are_jumpers no)
		(fp_line
			(start -0.299974 0.150114)
			(end -0.299974 -0.150114)
			(stroke
				(width 0.1)
				(type default)
			)
			(layer "F.Fab")
		)
		(fp_line
			(start 0.299974 0.150114)
			(end -0.299974 0.150114)
			(stroke
				(width 0.1)
				(type default)
			)
			(layer "F.Fab")
		)
		(fp_line
			(start -0.299974 -0.150114)
			(end 0.299974 -0.150114)
			(stroke
				(width 0.1)
				(type default)
			)
			(layer "F.Fab")
		)
		(fp_line
			(start 0.299974 -0.150114)
			(end 0.299974 0.150114)
			(stroke
				(width 0.1)
				(type default)
			)
			(layer "F.Fab")
		)
		(pad "1" smd rect
			(at -0.2667 0 270)
			(size 0.3048 0.381)
			(layers "F.Cu" "F.Mask" "F.Paste")
			(net "P5E_CPU0_PE4_TX_C_DP<3>")
		)
		(pad "2" smd rect
			(at 0.2667 0 270)
			(size 0.3048 0.381)
			(layers "F.Cu" "F.Mask" "F.Paste")
			(net "P5E_CPU0_PE4_TX_DP<3>")
		)
	)
	(footprint ""
		(layer "F.Cu")
		(at 83.338924 -152.621742 90)
		(property "Reference" "R661"
			(at 0 0 90)
			(layer "F.SilkS")
			(hide yes)
			(effects
				(font
					(size 1.27 1.27)
				)
			)
		)
		(property "Value" ""
			(at 0 0 90)
			(layer "F.Fab")
			(effects
				(font
					(size 1.27 1.27)
				)
			)
		)
		(duplicate_pad_numbers_are_jumpers no)
		(fp_line
			(start 0.7874 -0.4064)
			(end 0.7874 0.4064)
			(stroke
				(width 0.1524)
				(type default)
			)
			(layer "F.SilkS")
		)
		(fp_line
			(start -0.7874 -0.4064)
			(end 0.7874 -0.4064)
			(stroke
				(width 0.1524)
				(type default)
			)
			(layer "F.SilkS")
		)
		(fp_line
			(start 0.7874 0.4064)
			(end -0.7874 0.4064)
			(stroke
				(width 0.1524)
				(type default)
			)
			(layer "F.SilkS")
		)
		(fp_line
			(start -0.7874 0.4064)
			(end -0.7874 -0.4064)
			(stroke
				(width 0.1524)
				(type default)
			)
			(layer "F.SilkS")
		)
		(fp_line
			(start -0.12065 -0.305054)
			(end -0.12065 -0.2794)
			(stroke
				(width 0.1)
				(type default)
			)
			(layer "F.Fab")
		)
		(fp_line
			(start -0.67945 -0.305054)
			(end -0.12065 -0.305054)
			(stroke
				(width 0.1)
				(type default)
			)
			(layer "F.Fab")
		)
		(fp_line
			(start 0.67945 -0.3048)
			(end 0.67945 0.3048)
			(stroke
				(width 0.1)
				(type default)
			)
			(layer "F.Fab")
		)
		(fp_line
			(start 0.12065 -0.3048)
			(end 0.67945 -0.3048)
			(stroke
				(width 0.1)
				(type default)
			)
			(layer "F.Fab")
		)
		(fp_line
			(start 0.12065 -0.2794)
			(end 0.12065 -0.3048)
			(stroke
				(width 0.1)
				(type default)
			)
			(layer "F.Fab")
		)
		(fp_line
			(start -0.12065 -0.2794)
			(end 0.12065 -0.2794)
			(stroke
				(width 0.1)
				(type default)
			)
			(layer "F.Fab")
		)
		(fp_line
			(start 0.120396 0.2794)
			(end -0.12065 0.2794)
			(stroke
				(width 0.1)
				(type default)
			)
			(layer "F.Fab")
		)
		(fp_line
			(start -0.12065 0.2794)
			(end -0.12065 0.3048)
			(stroke
				(width 0.1)
				(type default)
			)
			(layer "F.Fab")
		)
		(fp_line
			(start 0.67945 0.3048)
			(end 0.120396 0.3048)
			(stroke
				(width 0.1)
				(type default)
			)
			(layer "F.Fab")
		)
		(fp_line
			(start 0.120396 0.3048)
			(end 0.120396 0.2794)
			(stroke
				(width 0.1)
				(type default)
			)
			(layer "F.Fab")
		)
		(fp_line
			(start -0.12065 0.3048)
			(end -0.67945 0.3048)
			(stroke
				(width 0.1)
				(type default)
			)
			(layer "F.Fab")
		)
		(fp_line
			(start -0.67945 0.3048)
			(end -0.67945 -0.305054)
			(stroke
				(width 0.1)
				(type default)
			)
			(layer "F.Fab")
		)
		(pad "1" smd circle
			(at -0.40005 0 90)
			(size 0 0)
			(layers "F.Cu" "F.Mask" "F.Paste")
			(net "PD_I3C_SPD_DDR_CPU1_OE_N")
		)
		(pad "2" smd circle
			(at 0.40005 0 90)
			(size 0 0)
			(layers "F.Cu" "F.Mask" "F.Paste")
			(net "GND")
		)
	)
	(footprint ""
		(layer "F.Cu")
		(at 51.25339 -353.547934)
		(property "Reference" "PU76_P1_2"
			(at 6.21411 -1.416304 0)
			(unlocked yes)
			(layer "F.SilkS")
			(effects
				(font
					(size 0.7874 0.5842)
					(thickness 0.1524)
				)
				(justify left)
			)
		)
		(property "Value" ""
			(at 0 0 0)
			(layer "F.Fab")
			(effects
				(font
					(size 1.27 1.27)
				)
			)
		)
		(duplicate_pad_numbers_are_jumpers no)
		(fp_line
			(start -2.500122 -2.999994)
			(end -2.24409 -2.999994)
			(stroke
				(width 0.1524)
				(type default)
			)
			(layer "F.SilkS")
		)
		(fp_line
			(start -2.500122 -2.529078)
			(end -2.500122 -2.999994)
			(stroke
				(width 0.1524)
				(type default)
			)
			(layer "F.SilkS")
		)
		(fp_line
			(start -2.500122 0.6604)
			(end -2.500122 0.229108)
			(stroke
				(width 0.1524)
				(type default)
			)
			(layer "F.SilkS")
		)
		(fp_line
			(start -2.500122 2.999994)
			(end -2.500122 2.339594)
			(stroke
				(width 0.1524)
				(type default)
			)
			(layer "F.SilkS")
		)
		(fp_line
			(start -2.2987 2.999994)
			(end -2.500122 2.999994)
			(stroke
				(width 0.1524)
				(type default)
			)
			(layer "F.SilkS")
		)
		(fp_line
			(start 2.31394 -2.999994)
			(end 2.500122 -2.999994)
			(stroke
				(width 0.1524)
				(type default)
			)
			(layer "F.SilkS")
		)
		(fp_line
			(start 2.500122 -2.999994)
			(end 2.500122 -2.44348)
			(stroke
				(width 0.1524)
				(type default)
			)
			(layer "F.SilkS")
		)
		(fp_line
			(start 2.500122 2.339594)
			(end 2.500122 2.999994)
			(stroke
				(width 0.1524)
				(type default)
			)
			(layer "F.SilkS")
		)
		(fp_line
			(start 2.500122 2.999994)
			(end 2.2987 2.999994)
			(stroke
				(width 0.1524)
				(type default)
			)
			(layer "F.SilkS")
		)
		(fp_poly
			(pts
				(xy -5.285232 -2.866898) (xy -4.269232 -2.358898) (xy -5.285232 -1.850898)
			)
			(stroke
				(width 0)
				(type default)
			)
			(fill yes)
			(layer "F.SilkS")
		)
		(fp_line
			(start -2.500122 -2.999994)
			(end 2.500122 -2.999994)
			(stroke
				(width 0.1)
				(type default)
			)
			(layer "F.Fab")
		)
		(fp_line
			(start -2.500122 2.999994)
			(end -2.500122 -2.999994)
			(stroke
				(width 0.1)
				(type default)
			)
			(layer "F.Fab")
		)
		(fp_line
			(start 2.500122 -2.999994)
			(end 2.500122 2.999994)
			(stroke
				(width 0.1)
				(type default)
			)
			(layer "F.Fab")
		)
		(fp_line
			(start 2.500122 2.999994)
			(end -2.500122 2.999994)
			(stroke
				(width 0.1)
				(type default)
			)
			(layer "F.Fab")
		)
		(fp_poly
			(pts
				(xy -4.218432 -2.783078) (xy -4.218432 -1.767078) (xy -3.202432 -2.275078)
			)
			(stroke
				(width 0)
				(type default)
			)
			(fill yes)
			(layer "F.Fab")
		)
		(pad "1" smd rect
			(at -2.400046 -2.275078 90)
			(size 0.2286 0.6096)
			(layers "F.Cu" "F.Mask" "F.Paste")
			(net "PVCCFA_EHV_FIVRA_CPU1_VOS2")
		)
		(pad "2" smd rect
			(at -2.400046 -1.82499 90)
			(size 0.2286 0.6096)
			(layers "F.Cu" "F.Mask" "F.Paste")
			(net "GND")
		)
		(pad "3" smd rect
			(at -2.400046 -1.374902 90)
			(size 0.2286 0.6096)
			(layers "F.Cu" "F.Mask" "F.Paste")
			(net "PVCCFA_EHV_FIVRA_CPU1_VDD2")
		)
		(pad "4" smd rect
			(at -2.400046 -0.925068 90)
			(size 0.2286 0.6096)
			(layers "F.Cu" "F.Mask" "F.Paste")
			(net "PVCCFA_EHV_FIVRA_CPU1_PVCC2")
		)
		(pad "5" smd rect
			(at -2.400046 -0.47498 90)
			(size 0.2286 0.6096)
			(layers "F.Cu" "F.Mask" "F.Paste")
			(net "GND")
		)
		(pad "6" smd rect
			(at -2.400046 -0.024892 90)
			(size 0.2286 0.6096)
			(layers "F.Cu" "F.Mask" "F.Paste")
			(net "Net_8502")
		)
		(pad "7_9-20_24" smd circle
			(at 0 1.150112 90)
			(size 0 0)
			(layers "F.Cu" "F.Mask" "F.Paste")
			(net "GND")
		)
		(pad "10_19" smd rect
			(at 0 2.899918 90)
			(size 0.6096 4.318)
			(layers "F.Cu" "F.Mask" "F.Paste")
			(net "SW_PVCCFA_EHV_FIVRA_CPU1_SW2")
		)
		(pad "25_29" smd rect
			(at 1.549908 -1.279906 270)
			(size 2.0574 2.3114)
			(layers "F.Cu" "F.Mask" "F.Paste")
			(net "SW_P12V_PVCCFA_EHV_FIVRA_CPU1_L")
		)
		(pad "30" smd rect
			(at 2.05994 -2.899918)
			(size 0.2286 0.6096)
			(layers "F.Cu" "F.Mask" "F.Paste")
			(net "SW_P12V_PVCCFA_EHV_FIVRA_CPU1_L")
		)
		(pad "31" smd rect
			(at 1.610106 -2.899918)
			(size 0.2286 0.6096)
			(layers "F.Cu" "F.Mask" "F.Paste")
			(net "Net_8503")
		)
		(pad "32" smd rect
			(at 1.160018 -2.899918)
			(size 0.2286 0.6096)
			(layers "F.Cu" "F.Mask" "F.Paste")
			(net "SW_PVCCFA_EHV_FIVRA_CPU1_BOOTR2")
		)
		(pad "33" smd rect
			(at 0.70993 -2.899918)
			(size 0.2286 0.6096)
			(layers "F.Cu" "F.Mask" "F.Paste")
			(net "SW_PVCCFA_EHV_FIVRA_CPU1_BOOT2")
		)
		(pad "34" smd rect
			(at 0.260096 -2.899918)
			(size 0.2286 0.6096)
			(layers "F.Cu" "F.Mask" "F.Paste")
			(net "PVCCFA_EHV_FIVRA_CPU1_PWM2")
		)
		(pad "35" smd rect
			(at -0.189992 -2.899918)
			(size 0.2286 0.6096)
			(layers "F.Cu" "F.Mask" "F.Paste")
			(net "PVCCFA_EHV_FIVRA_CPU1_VDD2")
		)
		(pad "36" smd rect
			(at -0.64008 -2.899918)
			(size 0.2286 0.6096)
			(layers "F.Cu" "F.Mask" "F.Paste")
			(net "PVCCFA_EHV_FIVRA_CPU1_BTSEN")
		)
		(pad "37" smd rect
			(at -1.089914 -2.899918)
			(size 0.2286 0.6096)
			(layers "F.Cu" "F.Mask" "F.Paste")
			(net "PVCCFA_EHV_FIVRA_CPU1_LSET2")
		)
		(pad "38" smd rect
			(at -1.540002 -2.899918)
			(size 0.2286 0.6096)
			(layers "F.Cu" "F.Mask" "F.Paste")
			(net "PVCCFA_EHV_FIVRA_CPU1_IMON2")
		)
		(pad "39" smd rect
			(at -1.99009 -2.899918)
			(size 0.2286 0.6096)
			(layers "F.Cu" "F.Mask" "F.Paste")
			(net "PVCCIN_CPU1_VREF")
		)
		(pad "40" smd rect
			(at -0.87503 -1.27508)
			(size 1.7526 1.9558)
			(layers "F.Cu" "F.Mask" "F.Paste")
			(net "GND")
		)
		(pad "41" smd rect
			(at -1.525016 0.249936 270)
			(size 0.3048 0.4572)
			(layers "F.Cu" "F.Mask" "F.Paste")
			(net "Net_8501")
		)
		(zone
			(layer "F.Cu")
			(hatch none 0.5)
			(connect_pads
				(clearance 0)
			)
			(min_thickness 0.25)
			(keepout
				(tracks not_allowed)
				(vias allowed)
				(pads allowed)
				(copperpour not_allowed)
				(footprints allowed)
			)
			(placement
				(enabled no)
				(sheetname "")
			)
			(fill
				(thermal_gap 0.5)
				(thermal_bridge_width 0.5)
				(island_removal_mode 0)
			)
			(polygon
				(pts
					(xy 48.753268 -350.54794) (xy 48.753268 -351.262188) (xy 53.753512 -351.262188) (xy 53.753512 -350.54794)
					(xy 53.46319 -350.54794) (xy 53.46319 -351.003616) (xy 49.04359 -351.003616) (xy 49.04359 -350.54794)
				)
			)
		)
		(zone
			(layer "F.Cu")
			(hatch none 0.5)
			(connect_pads
				(clearance 0)
			)
			(min_thickness 0.25)
			(keepout
				(tracks not_allowed)
				(vias allowed)
				(pads allowed)
				(copperpour not_allowed)
				(footprints allowed)
			)
			(placement
				(enabled no)
				(sheetname "")
			)
			(fill
				(thermal_gap 0.5)
				(thermal_bridge_width 0.5)
				(island_removal_mode 0)
			)
			(polygon
				(pts
					(xy 49.5046 -353.794314) (xy 50.27676 -353.794314) (xy 50.27676 -353.466908) (xy 50.302668 -353.466908)
					(xy 50.302668 -352.844862) (xy 50.25644 -352.798634) (xy 48.753268 -352.798634) (xy 48.753268 -353.255326)
					(xy 49.448974 -353.255326) (xy 49.448974 -353.094798) (xy 50.007774 -353.094798) (xy 50.007774 -353.501198)
					(xy 49.448974 -353.501198) (xy 49.448974 -353.280726) (xy 48.753268 -353.280726) (xy 48.753268 -353.407726)
					(xy 49.208944 -353.407726) (xy 49.208944 -353.774248) (xy 49.5046 -353.774248)
				)
			)
		)
	)
	(footprint ""
		(layer "F.Cu")
		(at 46.582584 -109.444282 180)
		(property "Reference" "R3005"
			(at 0 0 180)
			(layer "F.SilkS")
			(hide yes)
			(effects
				(font
					(size 1.27 1.27)
				)
			)
		)
		(property "Value" ""
			(at 0 0 180)
			(layer "F.Fab")
			(effects
				(font
					(size 1.27 1.27)
				)
			)
		)
		(duplicate_pad_numbers_are_jumpers no)
		(fp_line
			(start 0.7874 0.4064)
			(end -0.7874 0.4064)
			(stroke
				(width 0.1524)
				(type default)
			)
			(layer "F.SilkS")
		)
		(fp_line
			(start 0.7874 -0.4064)
			(end 0.7874 0.4064)
			(stroke
				(width 0.1524)
				(type default)
			)
			(layer "F.SilkS")
		)
		(fp_line
			(start -0.7874 0.4064)
			(end -0.7874 -0.4064)
			(stroke
				(width 0.1524)
				(type default)
			)
			(layer "F.SilkS")
		)
		(fp_line
			(start -0.7874 -0.4064)
			(end 0.7874 -0.4064)
			(stroke
				(width 0.1524)
				(type default)
			)
			(layer "F.SilkS")
		)
		(fp_line
			(start 0.67945 0.3048)
			(end 0.120396 0.3048)
			(stroke
				(width 0.1)
				(type default)
			)
			(layer "F.Fab")
		)
		(fp_line
			(start 0.67945 -0.3048)
			(end 0.67945 0.3048)
			(stroke
				(width 0.1)
				(type default)
			)
			(layer "F.Fab")
		)
		(fp_line
			(start 0.12065 -0.2794)
			(end 0.12065 -0.3048)
			(stroke
				(width 0.1)
				(type default)
			)
			(layer "F.Fab")
		)
		(fp_line
			(start 0.12065 -0.3048)
			(end 0.67945 -0.3048)
			(stroke
				(width 0.1)
				(type default)
			)
			(layer "F.Fab")
		)
		(fp_line
			(start 0.120396 0.3048)
			(end 0.120396 0.2794)
			(stroke
				(width 0.1)
				(type default)
			)
			(layer "F.Fab")
		)
		(fp_line
			(start 0.120396 0.2794)
			(end -0.12065 0.2794)
			(stroke
				(width 0.1)
				(type default)
			)
			(layer "F.Fab")
		)
		(fp_line
			(start -0.12065 0.3048)
			(end -0.67945 0.3048)
			(stroke
				(width 0.1)
				(type default)
			)
			(layer "F.Fab")
		)
		(fp_line
			(start -0.12065 0.2794)
			(end -0.12065 0.3048)
			(stroke
				(width 0.1)
				(type default)
			)
			(layer "F.Fab")
		)
		(fp_line
			(start -0.12065 -0.2794)
			(end 0.12065 -0.2794)
			(stroke
				(width 0.1)
				(type default)
			)
			(layer "F.Fab")
		)
		(fp_line
			(start -0.12065 -0.305054)
			(end -0.12065 -0.2794)
			(stroke
				(width 0.1)
				(type default)
			)
			(layer "F.Fab")
		)
		(fp_line
			(start -0.67945 0.3048)
			(end -0.67945 -0.305054)
			(stroke
				(width 0.1)
				(type default)
			)
			(layer "F.Fab")
		)
		(fp_line
			(start -0.67945 -0.305054)
			(end -0.12065 -0.305054)
			(stroke
				(width 0.1)
				(type default)
			)
			(layer "F.Fab")
		)
		(pad "1" smd circle
			(at -0.40005 0 180)
			(size 0 0)
			(layers "F.Cu" "F.Mask" "F.Paste")
			(net "P5V")
		)
		(pad "2" smd circle
			(at 0.40005 0 180)
			(size 0 0)
			(layers "F.Cu" "F.Mask" "F.Paste")
			(net "P5V_ADC")
		)
	)
)
